(kicad_pcb
	(version 20260206)
	(generator "pcbnew")
	(generator_version "10.0")
	(general
		(thickness 1.6)
		(legacy_teardrops no)
	)
	(paper "A4")
	(title_block
		(title "baseboard — 13948-1b.1110WZS1818.brd")
		(comment 1 "Honey Badger (Wiwynn) / footprints 683-691 of 2523")
	)
	(layers
		(0 "F.Cu" signal "TOP")
		(4 "In1.Cu" signal "L2GND")
		(6 "In2.Cu" signal "L3")
		(8 "In3.Cu" signal "L4VCC")
		(10 "In4.Cu" signal "L5VCC")
		(12 "In5.Cu" signal "L6")
		(14 "In6.Cu" signal "L7GND")
		(2 "B.Cu" signal "BOTTOM")
		(9 "F.Adhes" user "F.Adhesive")
		(11 "B.Adhes" user "B.Adhesive")
		(13 "F.Paste" user "Package Geometry/Pastemask Top")
		(15 "B.Paste" user "Package Geometry/Pastemask Bottom")
		(5 "F.SilkS" user "Ref Des/Silkscreen Top")
		(7 "B.SilkS" user "Ref Des/Silkscreen Bottom")
		(1 "F.Mask" user "Board Geometry/Soldermask Top")
		(3 "B.Mask" user "Board Geometry/Soldermask Bottom")
		(17 "Dwgs.User" user "User.Drawings")
		(19 "Cmts.User" user "User.Comments")
		(21 "Eco1.User" user "User.Eco1")
		(23 "Eco2.User" user "User.Eco2")
		(25 "Edge.Cuts" user "Board Geometry/Outline")
		(27 "Margin" user)
		(31 "F.CrtYd" user "Package Geometry/Place Bound Top")
		(29 "B.CrtYd" user "Package Geometry/Place Bound Bottom")
		(35 "F.Fab" user "Ref Des/Assembly Top")
		(33 "B.Fab" user "Ref Des/Assembly Bottom")
	)
	(footprint ""
		(layer "F.Cu")
		(at 264.033 -30.353 -90)
		(property "Reference" "PR54"
			(at 0 0 270)
			(layer "F.SilkS")
			(hide yes)
			(effects
				(font
					(size 1.27 1.27)
				)
			)
		)
		(property "Value" "0R2J-2-GP"
			(at 0.064008 -3.993896 270)
			(unlocked yes)
			(layer "F.Fab")
			(hide yes)
			(effects
				(font
					(size 1.016 1.016)
					(thickness 0.1524)
				)
			)
		)
		(property "Device Type" "R402H16"
			(at 0.064008 -5.517896 270)
			(unlocked yes)
			(layer "F.Fab")
			(hide yes)
			(effects
				(font
					(size 1.016 1.016)
					(thickness 0.1524)
				)
			)
		)
		(duplicate_pad_numbers_are_jumpers no)
		(fp_line
			(start -0.508 -0.9398)
			(end -0.508 0.9398)
			(stroke
				(width 0.1524)
				(type default)
			)
			(layer "F.SilkS")
		)
		(fp_line
			(start 0.508 -0.9398)
			(end -0.508 -0.9398)
			(stroke
				(width 0.1524)
				(type default)
			)
			(layer "F.SilkS")
		)
		(fp_rect
			(start -0.508 0.9398)
			(end 0.508 -0.9398)
			(stroke
				(width 0)
				(type default)
			)
			(fill no)
			(layer "F.CrtYd")
		)
		(fp_rect
			(start -0.508 0.9398)
			(end 0.508 -0.9398)
			(stroke
				(width 0)
				(type default)
			)
			(fill no)
			(layer "F.Fab")
		)
		(pad "1" smd custom
			(at 0 -0.4445 270)
			(size 0.1397 0.1397)
			(layers "F.Cu" "F.Mask" "F.Paste")
			(net "P1V8_STBY_ROVP")
			(options
				(clearance outline)
				(anchor circle)
			)
			(primitives
				(gr_poly
					(pts
						(arc
							(start -0.1778 -0.2794)
							(mid -0.249642 -0.249642)
							(end -0.2794 -0.1778)
						)
						(arc
							(start -0.2794 0.1778)
							(mid -0.249642 0.249642)
							(end -0.1778 0.2794)
						)
						(arc
							(start 0.1778 0.2794)
							(mid 0.249642 0.249642)
							(end 0.2794 0.1778)
						)
						(arc
							(start 0.2794 -0.1778)
							(mid 0.249642 -0.249642)
							(end 0.1778 -0.2794)
						)
					)
					(width 0)
					(fill yes)
				)
			)
		)
		(pad "2" smd custom
			(at 0 0.4445 270)
			(size 0.1397 0.1397)
			(layers "F.Cu" "F.Mask" "F.Paste")
			(net "P1V8_STBY")
			(options
				(clearance outline)
				(anchor circle)
			)
			(primitives
				(gr_poly
					(pts
						(arc
							(start -0.1778 -0.2794)
							(mid -0.249642 -0.249642)
							(end -0.2794 -0.1778)
						)
						(arc
							(start -0.2794 0.1778)
							(mid -0.249642 0.249642)
							(end -0.1778 0.2794)
						)
						(arc
							(start 0.1778 0.2794)
							(mid 0.249642 0.249642)
							(end 0.2794 0.1778)
						)
						(arc
							(start 0.2794 -0.1778)
							(mid 0.249642 -0.249642)
							(end 0.1778 -0.2794)
						)
					)
					(width 0)
					(fill yes)
				)
			)
		)
	)
	(footprint ""
		(layer "F.Cu")
		(at 89.281 -242.443 180)
		(property "Reference" "SR954"
			(at 0 0 180)
			(layer "F.SilkS")
			(hide yes)
			(effects
				(font
					(size 1.27 1.27)
				)
			)
		)
		(property "Value" "4K7R2F-GP"
			(at 0.064008 -3.993896 180)
			(unlocked yes)
			(layer "F.Fab")
			(hide yes)
			(effects
				(font
					(size 1.016 1.016)
					(thickness 0.1524)
				)
			)
		)
		(property "Device Type" "R402H16"
			(at 0.064008 -5.517896 180)
			(unlocked yes)
			(layer "F.Fab")
			(hide yes)
			(effects
				(font
					(size 1.016 1.016)
					(thickness 0.1524)
				)
			)
		)
		(duplicate_pad_numbers_are_jumpers no)
		(fp_line
			(start 0.508 -0.9398)
			(end -0.508 -0.9398)
			(stroke
				(width 0.1524)
				(type default)
			)
			(layer "F.SilkS")
		)
		(fp_line
			(start -0.508 -0.9398)
			(end -0.508 0.9398)
			(stroke
				(width 0.1524)
				(type default)
			)
			(layer "F.SilkS")
		)
		(fp_rect
			(start -0.508 0.9398)
			(end 0.508 -0.9398)
			(stroke
				(width 0)
				(type default)
			)
			(fill no)
			(layer "F.CrtYd")
		)
		(fp_rect
			(start -0.508 0.9398)
			(end 0.508 -0.9398)
			(stroke
				(width 0)
				(type default)
			)
			(fill no)
			(layer "F.Fab")
		)
		(pad "1" smd custom
			(at 0 -0.4445 180)
			(size 0.1397 0.1397)
			(layers "F.Cu" "F.Mask" "F.Paste")
			(net "SAS_FAULT_LED13")
			(options
				(clearance outline)
				(anchor circle)
			)
			(primitives
				(gr_poly
					(pts
						(arc
							(start -0.1778 -0.2794)
							(mid -0.249642 -0.249642)
							(end -0.2794 -0.1778)
						)
						(arc
							(start -0.2794 0.1778)
							(mid -0.249642 0.249642)
							(end -0.1778 0.2794)
						)
						(arc
							(start 0.1778 0.2794)
							(mid 0.249642 0.249642)
							(end 0.2794 0.1778)
						)
						(arc
							(start 0.2794 -0.1778)
							(mid 0.249642 -0.249642)
							(end 0.1778 -0.2794)
						)
					)
					(width 0)
					(fill yes)
				)
			)
		)
		(pad "2" smd custom
			(at 0 0.4445 180)
			(size 0.1397 0.1397)
			(layers "F.Cu" "F.Mask" "F.Paste")
			(net "P3V3_STBY")
			(options
				(clearance outline)
				(anchor circle)
			)
			(primitives
				(gr_poly
					(pts
						(arc
							(start -0.1778 -0.2794)
							(mid -0.249642 -0.249642)
							(end -0.2794 -0.1778)
						)
						(arc
							(start -0.2794 0.1778)
							(mid -0.249642 0.249642)
							(end -0.1778 0.2794)
						)
						(arc
							(start 0.1778 0.2794)
							(mid 0.249642 0.249642)
							(end 0.2794 0.1778)
						)
						(arc
							(start 0.2794 -0.1778)
							(mid 0.249642 -0.249642)
							(end 0.1778 -0.2794)
						)
					)
					(width 0)
					(fill yes)
				)
			)
		)
	)
	(footprint ""
		(layer "F.Cu")
		(at 280.289 -196.215 -90)
		(property "Reference" "C196"
			(at 0 0 270)
			(layer "F.SilkS")
			(hide yes)
			(effects
				(font
					(size 1.27 1.27)
				)
			)
		)
		(property "Value" "SC100P50V2JN-3GP"
			(at 1.1811 -2.7051 270)
			(unlocked yes)
			(layer "F.Fab")
			(hide yes)
			(effects
				(font
					(size 1.016 1.016)
					(thickness 0.1524)
				)
			)
		)
		(property "Device Type" "C402H22"
			(at 1.1811 -4.2291 270)
			(unlocked yes)
			(layer "F.Fab")
			(hide yes)
			(effects
				(font
					(size 1.016 1.016)
					(thickness 0.1524)
				)
			)
		)
		(duplicate_pad_numbers_are_jumpers no)
		(fp_rect
			(start -0.4318 0.9525)
			(end 0.4318 -0.9525)
			(stroke
				(width 0)
				(type default)
			)
			(fill no)
			(layer "F.CrtYd")
		)
		(fp_rect
			(start -0.4318 0.9525)
			(end 0.4318 -0.9525)
			(stroke
				(width 0)
				(type default)
			)
			(fill no)
			(layer "F.Fab")
		)
		(pad "1" smd custom
			(at 0 -0.4445 270)
			(size 0.1524 0.1524)
			(layers "F.Cu" "F.Mask" "F.Paste")
			(net "MPLLAV33")
			(options
				(clearance outline)
				(anchor circle)
			)
			(primitives
				(gr_poly
					(pts
						(arc
							(start 0.3048 -0.2032)
							(mid 0.275042 -0.275042)
							(end 0.2032 -0.3048)
						)
						(arc
							(start -0.2032 -0.3048)
							(mid -0.275042 -0.275042)
							(end -0.3048 -0.2032)
						)
						(arc
							(start -0.3048 0.2032)
							(mid -0.275042 0.275042)
							(end -0.2032 0.3048)
						)
						(arc
							(start 0.2032 0.3048)
							(mid 0.275042 0.275042)
							(end 0.3048 0.2032)
						)
					)
					(width 0)
					(fill yes)
				)
			)
		)
		(pad "2" smd custom
			(at 0 0.4445 270)
			(size 0.1524 0.1524)
			(layers "F.Cu" "F.Mask" "F.Paste")
			(net "GND")
			(options
				(clearance outline)
				(anchor circle)
			)
			(primitives
				(gr_poly
					(pts
						(arc
							(start 0.3048 -0.2032)
							(mid 0.275042 -0.275042)
							(end 0.2032 -0.3048)
						)
						(arc
							(start -0.2032 -0.3048)
							(mid -0.275042 -0.275042)
							(end -0.3048 -0.2032)
						)
						(arc
							(start -0.3048 0.2032)
							(mid -0.275042 0.275042)
							(end -0.2032 0.3048)
						)
						(arc
							(start 0.2032 0.3048)
							(mid 0.275042 0.275042)
							(end 0.3048 0.2032)
						)
					)
					(width 0)
					(fill yes)
				)
			)
		)
	)
	(footprint ""
		(layer "F.Cu")
		(at 314.071 -192.405)
		(property "Reference" "TP177"
			(at 0 0 0)
			(layer "F.SilkS")
			(hide yes)
			(effects
				(font
					(size 1.27 1.27)
				)
			)
		)
		(property "Value" "TPAD28"
			(at -0.0127 -1.6637 0)
			(unlocked yes)
			(layer "F.Fab")
			(hide yes)
			(effects
				(font
					(size 1.016 1.016)
					(thickness 0.1524)
				)
			)
		)
		(property "Device Type" "TPAD28"
			(at -0.0127 -3.1877 0)
			(unlocked yes)
			(layer "F.Fab")
			(hide yes)
			(effects
				(font
					(size 1.016 1.016)
					(thickness 0.1524)
				)
			)
		)
		(duplicate_pad_numbers_are_jumpers no)
		(fp_poly
			(pts
				(arc
					(start 0.3556 0)
					(mid -0.3556 0)
					(end 0.3556 0)
				)
			)
			(stroke
				(width 0)
				(type default)
			)
			(fill no)
			(layer "F.CrtYd")
		)
		(fp_poly
			(pts
				(arc
					(start 0.6096 0)
					(mid -0.6096 0)
					(end 0.6096 0)
				)
			)
			(stroke
				(width 0)
				(type default)
			)
			(fill no)
			(layer "F.Fab")
		)
		(pad "1" smd circle
			(at 0 0)
			(size 0.7112 0.7112)
			(layers "F.Cu" "F.Mask" "F.Paste")
			(net "JTAG_BMC_TMS")
		)
	)
	(footprint ""
		(layer "F.Cu")
		(at 293.497 -161.544 180)
		(property "Reference" "R281"
			(at 0 0 180)
			(layer "F.SilkS")
			(hide yes)
			(effects
				(font
					(size 1.27 1.27)
				)
			)
		)
		(property "Value" "0R2J-2-GP"
			(at 0.064008 -3.993896 180)
			(unlocked yes)
			(layer "F.Fab")
			(hide yes)
			(effects
				(font
					(size 1.016 1.016)
					(thickness 0.1524)
				)
			)
		)
		(property "Device Type" "R402H16"
			(at 0.064008 -5.517896 180)
			(unlocked yes)
			(layer "F.Fab")
			(hide yes)
			(effects
				(font
					(size 1.016 1.016)
					(thickness 0.1524)
				)
			)
		)
		(duplicate_pad_numbers_are_jumpers no)
		(fp_line
			(start 0.508 -0.9398)
			(end -0.508 -0.9398)
			(stroke
				(width 0.1524)
				(type default)
			)
			(layer "F.SilkS")
		)
		(fp_line
			(start -0.508 -0.9398)
			(end -0.508 0.9398)
			(stroke
				(width 0.1524)
				(type default)
			)
			(layer "F.SilkS")
		)
		(fp_rect
			(start -0.508 0.9398)
			(end 0.508 -0.9398)
			(stroke
				(width 0)
				(type default)
			)
			(fill no)
			(layer "F.CrtYd")
		)
		(fp_rect
			(start -0.508 0.9398)
			(end 0.508 -0.9398)
			(stroke
				(width 0)
				(type default)
			)
			(fill no)
			(layer "F.Fab")
		)
		(pad "1" smd custom
			(at 0 -0.4445 180)
			(size 0.1397 0.1397)
			(layers "F.Cu" "F.Mask" "F.Paste")
			(net "RMII_BMC_TX_EN")
			(options
				(clearance outline)
				(anchor circle)
			)
			(primitives
				(gr_poly
					(pts
						(arc
							(start -0.1778 -0.2794)
							(mid -0.249642 -0.249642)
							(end -0.2794 -0.1778)
						)
						(arc
							(start -0.2794 0.1778)
							(mid -0.249642 0.249642)
							(end -0.1778 0.2794)
						)
						(arc
							(start 0.1778 0.2794)
							(mid 0.249642 0.249642)
							(end 0.2794 0.1778)
						)
						(arc
							(start 0.2794 -0.1778)
							(mid 0.249642 -0.249642)
							(end 0.1778 -0.2794)
						)
					)
					(width 0)
					(fill yes)
				)
			)
		)
		(pad "2" smd custom
			(at 0 0.4445 180)
			(size 0.1397 0.1397)
			(layers "F.Cu" "F.Mask" "F.Paste")
			(net "RMII0_BMC_C_TX_EN")
			(options
				(clearance outline)
				(anchor circle)
			)
			(primitives
				(gr_poly
					(pts
						(arc
							(start -0.1778 -0.2794)
							(mid -0.249642 -0.249642)
							(end -0.2794 -0.1778)
						)
						(arc
							(start -0.2794 0.1778)
							(mid -0.249642 0.249642)
							(end -0.1778 0.2794)
						)
						(arc
							(start 0.1778 0.2794)
							(mid 0.249642 0.249642)
							(end 0.2794 0.1778)
						)
						(arc
							(start 0.2794 -0.1778)
							(mid 0.249642 -0.249642)
							(end 0.1778 -0.2794)
						)
					)
					(width 0)
					(fill yes)
				)
			)
		)
	)
	(footprint ""
		(layer "F.Cu")
		(at 83.57997 -140.843 180)
		(property "Reference" "SR920"
			(at 0 0 180)
			(layer "F.SilkS")
			(hide yes)
			(effects
				(font
					(size 1.27 1.27)
				)
			)
		)
		(property "Value" "0R2J-2-GP"
			(at 0.064008 -3.993896 180)
			(unlocked yes)
			(layer "F.Fab")
			(hide yes)
			(effects
				(font
					(size 1.016 1.016)
					(thickness 0.1524)
				)
			)
		)
		(property "Device Type" "R402H16"
			(at 0.064008 -5.517896 180)
			(unlocked yes)
			(layer "F.Fab")
			(hide yes)
			(effects
				(font
					(size 1.016 1.016)
					(thickness 0.1524)
				)
			)
		)
		(duplicate_pad_numbers_are_jumpers no)
		(fp_line
			(start 0.508 -0.9398)
			(end -0.508 -0.9398)
			(stroke
				(width 0.1524)
				(type default)
			)
			(layer "F.SilkS")
		)
		(fp_line
			(start -0.508 -0.9398)
			(end -0.508 0.9398)
			(stroke
				(width 0.1524)
				(type default)
			)
			(layer "F.SilkS")
		)
		(fp_rect
			(start -0.508 0.9398)
			(end 0.508 -0.9398)
			(stroke
				(width 0)
				(type default)
			)
			(fill no)
			(layer "F.CrtYd")
		)
		(fp_rect
			(start -0.508 0.9398)
			(end 0.508 -0.9398)
			(stroke
				(width 0)
				(type default)
			)
			(fill no)
			(layer "F.Fab")
		)
		(pad "1" smd custom
			(at 0 -0.4445 180)
			(size 0.1397 0.1397)
			(layers "F.Cu" "F.Mask" "F.Paste")
			(net "FAN_PWM_PCIE_R")
			(options
				(clearance outline)
				(anchor circle)
			)
			(primitives
				(gr_poly
					(pts
						(arc
							(start -0.1778 -0.2794)
							(mid -0.249642 -0.249642)
							(end -0.2794 -0.1778)
						)
						(arc
							(start -0.2794 0.1778)
							(mid -0.249642 0.249642)
							(end -0.1778 0.2794)
						)
						(arc
							(start 0.1778 0.2794)
							(mid 0.249642 0.249642)
							(end 0.2794 0.1778)
						)
						(arc
							(start 0.2794 -0.1778)
							(mid 0.249642 -0.249642)
							(end 0.1778 -0.2794)
						)
					)
					(width 0)
					(fill yes)
				)
			)
		)
		(pad "2" smd custom
			(at 0 0.4445 180)
			(size 0.1397 0.1397)
			(layers "F.Cu" "F.Mask" "F.Paste")
			(net "FAN_PWM_PCIE")
			(options
				(clearance outline)
				(anchor circle)
			)
			(primitives
				(gr_poly
					(pts
						(arc
							(start -0.1778 -0.2794)
							(mid -0.249642 -0.249642)
							(end -0.2794 -0.1778)
						)
						(arc
							(start -0.2794 0.1778)
							(mid -0.249642 0.249642)
							(end -0.1778 0.2794)
						)
						(arc
							(start 0.1778 0.2794)
							(mid 0.249642 0.249642)
							(end 0.2794 0.1778)
						)
						(arc
							(start 0.2794 -0.1778)
							(mid 0.249642 -0.249642)
							(end 0.1778 -0.2794)
						)
					)
					(width 0)
					(fill yes)
				)
			)
		)
	)
	(footprint ""
		(layer "F.Cu")
		(at 267.643864 -70.603872 90)
		(property "Reference" "C253"
			(at 0 0 90)
			(layer "F.SilkS")
			(hide yes)
			(effects
				(font
					(size 1.27 1.27)
				)
			)
		)
		(property "Value" "SC1U25V3KX-GP"
			(at 0 -2.8194 90)
			(unlocked yes)
			(layer "F.Fab")
			(hide yes)
			(effects
				(font
					(size 1.016 1.016)
					(thickness 0.1524)
				)
			)
		)
		(property "Device Type" "C603H36"
			(at 0 -4.3434 90)
			(unlocked yes)
			(layer "F.Fab")
			(hide yes)
			(effects
				(font
					(size 1.016 1.016)
					(thickness 0.1524)
				)
			)
		)
		(duplicate_pad_numbers_are_jumpers no)
		(fp_line
			(start 0.508 0)
			(end -0.508 0)
			(stroke
				(width 0.2032)
				(type default)
			)
			(layer "F.SilkS")
		)
		(fp_rect
			(start -0.5842 1.3335)
			(end 0.5842 -1.3335)
			(stroke
				(width 0)
				(type default)
			)
			(fill no)
			(layer "F.CrtYd")
		)
		(fp_rect
			(start -0.5842 1.3335)
			(end 0.5842 -1.3335)
			(stroke
				(width 0)
				(type default)
			)
			(fill no)
			(layer "F.Fab")
		)
		(pad "1" smd custom
			(at 0 -0.762 90)
			(size 0.2159 0.2159)
			(layers "F.Cu" "F.Mask" "F.Paste")
			(net "P12V_MSB")
			(options
				(clearance outline)
				(anchor circle)
			)
			(primitives
				(gr_poly
					(pts
						(arc
							(start -0.3302 -0.4318)
							(mid -0.402042 -0.402042)
							(end -0.4318 -0.3302)
						)
						(arc
							(start -0.4318 0.3302)
							(mid -0.402042 0.402042)
							(end -0.3302 0.4318)
						)
						(arc
							(start 0.3302 0.4318)
							(mid 0.402042 0.402042)
							(end 0.4318 0.3302)
						)
						(arc
							(start 0.4318 -0.3302)
							(mid 0.402042 -0.402042)
							(end 0.3302 -0.4318)
						)
					)
					(width 0)
					(fill yes)
				)
			)
		)
		(pad "2" smd custom
			(at 0 0.762 90)
			(size 0.2159 0.2159)
			(layers "F.Cu" "F.Mask" "F.Paste")
			(net "GND")
			(options
				(clearance outline)
				(anchor circle)
			)
			(primitives
				(gr_poly
					(pts
						(arc
							(start -0.3302 -0.4318)
							(mid -0.402042 -0.402042)
							(end -0.4318 -0.3302)
						)
						(arc
							(start -0.4318 0.3302)
							(mid -0.402042 0.402042)
							(end -0.3302 0.4318)
						)
						(arc
							(start 0.3302 0.4318)
							(mid 0.402042 0.402042)
							(end 0.4318 0.3302)
						)
						(arc
							(start 0.4318 -0.3302)
							(mid 0.402042 -0.402042)
							(end 0.3302 -0.4318)
						)
					)
					(width 0)
					(fill yes)
				)
			)
		)
	)
	(footprint ""
		(layer "F.Cu")
		(at 266.500864 -230.369872 90)
		(property "Reference" "PC91"
			(at 0 0 90)
			(layer "F.SilkS")
			(hide yes)
			(effects
				(font
					(size 1.27 1.27)
				)
			)
		)
		(property "Value" "SC10U6D3V5KX-1GP"
			(at -0.0762 -6.1214 90)
			(unlocked yes)
			(layer "F.Fab")
			(hide yes)
			(effects
				(font
					(size 1.016 1.016)
					(thickness 0.1524)
				)
			)
		)
		(property "Device Type" "C805H54"
			(at -0.0762 -8.1534 90)
			(unlocked yes)
			(layer "F.Fab")
			(hide yes)
			(effects
				(font
					(size 1.016 1.016)
					(thickness 0.1524)
				)
			)
		)
		(duplicate_pad_numbers_are_jumpers no)
		(fp_line
			(start 0.635 0)
			(end -0.635 0)
			(stroke
				(width 0.508)
				(type default)
			)
			(layer "F.SilkS")
		)
		(fp_rect
			(start -0.9652 1.778)
			(end 0.9652 -1.778)
			(stroke
				(width 0)
				(type default)
			)
			(fill no)
			(layer "F.CrtYd")
		)
		(fp_poly
			(pts
				(xy -0.9652 -1.778) (xy 0.9652 -1.778) (xy 0.9652 1.778) (xy -0.9652 1.778)
			)
			(stroke
				(width 0)
				(type default)
			)
			(fill no)
			(layer "F.Fab")
		)
		(pad "1" smd rect
			(at 0 -0.9652 90)
			(size 1.397 1.143)
			(layers "F.Cu" "F.Mask" "F.Paste")
			(net "TPS74801_P1V26_STBY_IN")
		)
		(pad "2" smd rect
			(at 0 0.9652 90)
			(size 1.397 1.143)
			(layers "F.Cu" "F.Mask" "F.Paste")
			(net "GND")
		)
	)
	(footprint ""
		(layer "F.Cu")
		(at 320.294 -144.907 90)
		(property "Reference" "C1698"
			(at 0 0 90)
			(layer "F.SilkS")
			(hide yes)
			(effects
				(font
					(size 1.27 1.27)
				)
			)
		)
		(property "Value" "SC22U6D3V5MX-2GP"
			(at -0.0762 -6.1214 90)
			(unlocked yes)
			(layer "F.Fab")
			(hide yes)
			(effects
				(font
					(size 1.016 1.016)
					(thickness 0.1524)
				)
			)
		)
		(property "Device Type" "C805H58"
			(at -0.0762 -8.1534 90)
			(unlocked yes)
			(layer "F.Fab")
			(hide yes)
			(effects
				(font
					(size 1.016 1.016)
					(thickness 0.1524)
				)
			)
		)
		(duplicate_pad_numbers_are_jumpers no)
		(fp_line
			(start 0.635 0)
			(end -0.635 0)
			(stroke
				(width 0.508)
				(type default)
			)
			(layer "F.SilkS")
		)
		(fp_rect
			(start -0.9652 1.778)
			(end 0.9652 -1.778)
			(stroke
				(width 0)
				(type default)
			)
			(fill no)
			(layer "F.CrtYd")
		)
		(fp_poly
			(pts
				(xy -0.9652 -1.778) (xy 0.9652 -1.778) (xy 0.9652 1.778) (xy -0.9652 1.778)
			)
			(stroke
				(width 0)
				(type default)
			)
			(fill no)
			(layer "F.Fab")
		)
		(pad "1" smd rect
			(at 0 -0.9652 90)
			(size 1.397 1.143)
			(layers "F.Cu" "F.Mask" "F.Paste")
			(net "P3V3_RTC")
		)
		(pad "2" smd rect
			(at 0 0.9652 90)
			(size 1.397 1.143)
			(layers "F.Cu" "F.Mask" "F.Paste")
			(net "GND")
		)
	)
)
